(kicad_pcb
	(version 20260206)
	(generator "pcbnew")
	(generator_version "10.0")
	(general
		(thickness 1.6)
		(legacy_teardrops no)
	)
	(paper "A4")
	(title_block
		(title "panther-plus-userver — 13130-1b_20150205.brd")
		(comment 1 "Honey Badger (Wiwynn) / footprint 406 of 1509 (DIMM2), pads 58-64 of 210")
	)
	(layers
		(0 "F.Cu" signal "TOP")
		(4 "In1.Cu" signal "L2")
		(6 "In2.Cu" signal "L3")
		(8 "In3.Cu" signal "L4")
		(10 "In4.Cu" signal "L5")
		(12 "In5.Cu" signal "L6")
		(14 "In6.Cu" signal "L7")
		(16 "In7.Cu" signal "L8")
		(18 "In8.Cu" signal "L9")
		(20 "In9.Cu" signal "L10")
		(22 "In10.Cu" signal "L11")
		(2 "B.Cu" signal "BOTTOM")
		(9 "F.Adhes" user "F.Adhesive")
		(11 "B.Adhes" user "B.Adhesive")
		(13 "F.Paste" user "Package Geometry/Pastemask Top")
		(15 "B.Paste" user "Package Geometry/Pastemask Bottom")
		(5 "F.SilkS" user "Ref Des/Silkscreen Top")
		(7 "B.SilkS" user "Ref Des/Silkscreen Bottom")
		(1 "F.Mask" user "Board Geometry/Soldermask Top")
		(3 "B.Mask" user "Board Geometry/Soldermask Bottom")
		(17 "Dwgs.User" user "User.Drawings")
		(19 "Cmts.User" user "User.Comments")
		(21 "Eco1.User" user "User.Eco1")
		(23 "Eco2.User" user "User.Eco2")
		(25 "Edge.Cuts" user "Board Geometry/Outline")
		(27 "Margin" user)
		(31 "F.CrtYd" user "Package Geometry/Place Bound Top")
		(29 "B.CrtYd" user "Package Geometry/Place Bound Bottom")
		(35 "F.Fab" user "Ref Des/Assembly Top")
		(33 "B.Fab" user "Ref Des/Assembly Bottom")
	)
	(footprint ""
		(layer "F.Cu")
		(at 158.500064 -66.699892 180)
		(property "Reference" "DIMM2"
			(at 0 0 180)
			(layer "F.SilkS")
			(hide yes)
			(effects
				(font
					(size 1.27 1.27)
				)
			)
		)
		(property "Value" "DDR3-204P-174-COLAY-1-GP"
			(at -40.682164 -17.468088 180)
			(unlocked yes)
			(layer "F.Fab")
			(hide yes)
			(effects
				(font
					(size 1.016 1.016)
					(thickness 0.1524)
				)
			)
		)
		(property "Device Type" "AS0A626-H8SN-7H-COLAY-1"
			(at -40.682164 -18.992088 180)
			(unlocked yes)
			(layer "F.Fab")
			(hide yes)
			(effects
				(font
					(size 1.016 1.016)
					(thickness 0.1524)
				)
			)
		)
		(duplicate_pad_numbers_are_jumpers no)
		(pad "56" smd custom
			(at -15.150084 -4.106672 180)
			(size 0.1143 0.1143)
			(layers "F.Cu" "F.Mask" "F.Paste")
			(net "M_A_DQ25")
			(options
				(clearance outline)
				(anchor circle)
			)
			(primitives
				(gr_poly
					(pts
						(xy 0 0.9017) (xy -0.03175 0.89916) (xy -0.0635 0.889) (xy -0.09144 0.87376) (xy -0.11684 0.85344)
						(xy -0.13716 0.82804) (xy -0.1524 0.8001) (xy -0.16256 0.76835) (xy -0.1651 0.7366) (xy -0.1651 0.19685)
						(xy -0.17272 0.18923) (xy -0.17907 0.18034) (xy -0.18669 0.17145) (xy -0.19177 0.16256) (xy -0.19812 0.15367)
						(xy -0.20828 0.13335) (xy -0.21971 0.10287) (xy -0.22225 0.09271) (xy -0.22479 0.08128) (xy -0.22606 0.07112)
						(xy -0.2286 0.05969) (xy -0.2286 0.01651) (xy -0.22606 0.00508) (xy -0.22479 -0.00508) (xy -0.22225 -0.01651)
						(xy -0.21971 -0.02667) (xy -0.20828 -0.05715) (xy -0.19812 -0.07747) (xy -0.19177 -0.08636) (xy -0.18669 -0.09525)
						(xy -0.17907 -0.10414) (xy -0.17272 -0.11303) (xy -0.1651 -0.12065) (xy -0.1651 -0.7366) (xy -0.16256 -0.76835)
						(xy -0.1524 -0.8001) (xy -0.13716 -0.82804) (xy -0.11684 -0.85344) (xy -0.09144 -0.87376) (xy -0.0635 -0.889)
						(xy -0.03175 -0.89916) (xy 0 -0.9017) (xy 0.03175 -0.89916) (xy 0.0635 -0.889) (xy 0.09144 -0.87376)
						(xy 0.11684 -0.85344) (xy 0.13716 -0.82804) (xy 0.1524 -0.8001) (xy 0.16256 -0.76835) (xy 0.1651 -0.7366)
						(xy 0.1651 -0.11938) (xy 0.17272 -0.11176) (xy 0.19812 -0.0762) (xy 0.2032 -0.06604) (xy 0.20701 -0.05715)
						(xy 0.21209 -0.04699) (xy 0.2159 -0.03683) (xy 0.21844 -0.02667) (xy 0.22225 -0.01524) (xy 0.22352 -0.00508)
						(xy 0.22606 0.00508) (xy 0.22733 0.01651) (xy 0.22733 0.02667) (xy 0.2286 0.0381) (xy 0.22733 0.04953)
						(xy 0.22733 0.05969) (xy 0.22606 0.07112) (xy 0.22352 0.08128) (xy 0.22225 0.09144) (xy 0.21844 0.10287)
						(xy 0.2159 0.11303) (xy 0.21209 0.12319) (xy 0.20701 0.13335) (xy 0.2032 0.14224) (xy 0.19812 0.1524)
						(xy 0.17272 0.18796) (xy 0.1651 0.19558) (xy 0.1651 0.7366) (xy 0.16256 0.76835) (xy 0.1524 0.8001)
						(xy 0.13716 0.82804) (xy 0.11684 0.85344) (xy 0.09144 0.87376) (xy 0.0635 0.889) (xy 0.03175 0.89916)
					)
					(width 0)
					(fill yes)
				)
			)
		)
		(pad "57" smd custom
			(at -14.85011 4.106672 180)
			(size 0.1143 0.1143)
			(layers "F.Cu" "F.Mask" "F.Paste")
			(net "M_A_DQ29")
			(options
				(clearance outline)
				(anchor circle)
			)
			(primitives
				(gr_poly
					(pts
						(xy 0 0.9017) (xy -0.03175 0.89916) (xy -0.0635 0.889) (xy -0.09144 0.87376) (xy -0.11684 0.85344)
						(xy -0.13716 0.82804) (xy -0.1524 0.8001) (xy -0.16256 0.76835) (xy -0.1651 0.7366) (xy -0.1651 -0.13462)
						(xy -0.17272 -0.14224) (xy -0.19812 -0.1778) (xy -0.2032 -0.18796) (xy -0.20701 -0.19685) (xy -0.21209 -0.20701)
						(xy -0.2159 -0.21717) (xy -0.21844 -0.22733) (xy -0.22225 -0.23876) (xy -0.22352 -0.24892) (xy -0.22606 -0.25908)
						(xy -0.22733 -0.27051) (xy -0.22733 -0.28067) (xy -0.2286 -0.2921) (xy -0.22733 -0.30353) (xy -0.22733 -0.31369)
						(xy -0.22606 -0.32512) (xy -0.22352 -0.33528) (xy -0.22225 -0.34544) (xy -0.21844 -0.35687) (xy -0.2159 -0.36703)
						(xy -0.21209 -0.37719) (xy -0.20701 -0.38735) (xy -0.2032 -0.39624) (xy -0.19812 -0.4064) (xy -0.17272 -0.44196)
						(xy -0.1651 -0.44958) (xy -0.1651 -0.7366) (xy -0.16256 -0.76835) (xy -0.1524 -0.8001) (xy -0.13716 -0.82804)
						(xy -0.11684 -0.85344) (xy -0.09144 -0.87376) (xy -0.0635 -0.889) (xy -0.03175 -0.89916) (xy 0 -0.9017)
						(xy 0.03175 -0.89916) (xy 0.0635 -0.889) (xy 0.09144 -0.87376) (xy 0.11684 -0.85344) (xy 0.13716 -0.82804)
						(xy 0.1524 -0.8001) (xy 0.16256 -0.76835) (xy 0.1651 -0.7366) (xy 0.1651 -0.44958) (xy 0.17272 -0.44196)
						(xy 0.19812 -0.4064) (xy 0.2032 -0.39624) (xy 0.20701 -0.38735) (xy 0.21209 -0.37719) (xy 0.2159 -0.36703)
						(xy 0.21844 -0.35687) (xy 0.22225 -0.34544) (xy 0.22352 -0.33528) (xy 0.22606 -0.32512) (xy 0.22733 -0.31369)
						(xy 0.22733 -0.30353) (xy 0.2286 -0.2921) (xy 0.22733 -0.28067) (xy 0.22733 -0.27051) (xy 0.22606 -0.25908)
						(xy 0.22352 -0.24892) (xy 0.22225 -0.23876) (xy 0.21844 -0.22733) (xy 0.2159 -0.21717) (xy 0.21209 -0.20701)
						(xy 0.20701 -0.19685) (xy 0.2032 -0.18796) (xy 0.19812 -0.1778) (xy 0.17272 -0.14224) (xy 0.1651 -0.13462)
						(xy 0.1651 0.7366) (xy 0.16256 0.76835) (xy 0.1524 0.8001) (xy 0.13716 0.82804) (xy 0.11684 0.85344)
						(xy 0.09144 0.87376) (xy 0.0635 0.889) (xy 0.03175 0.89916)
					)
					(width 0)
					(fill yes)
				)
			)
		)
		(pad "58" smd custom
			(at -14.549882 -4.106672 180)
			(size 0.1143 0.1143)
			(layers "F.Cu" "F.Mask" "F.Paste")
			(net "GND")
			(options
				(clearance outline)
				(anchor circle)
			)
			(primitives
				(gr_poly
					(pts
						(xy 0 0.9017) (xy -0.03175 0.89916) (xy -0.0635 0.889) (xy -0.09144 0.87376) (xy -0.11684 0.85344)
						(xy -0.13716 0.82804) (xy -0.1524 0.8001) (xy -0.16256 0.76835) (xy -0.1651 0.7366) (xy -0.1651 0.44958)
						(xy -0.17272 0.44196) (xy -0.19812 0.4064) (xy -0.2032 0.39624) (xy -0.20701 0.38735) (xy -0.21209 0.37719)
						(xy -0.2159 0.36703) (xy -0.21844 0.35687) (xy -0.22225 0.34544) (xy -0.22352 0.33528) (xy -0.22606 0.32512)
						(xy -0.22733 0.31369) (xy -0.22733 0.30353) (xy -0.2286 0.2921) (xy -0.22733 0.28067) (xy -0.22733 0.27051)
						(xy -0.22606 0.25908) (xy -0.22352 0.24892) (xy -0.22225 0.23876) (xy -0.21844 0.22733) (xy -0.2159 0.21717)
						(xy -0.21209 0.20701) (xy -0.20701 0.19685) (xy -0.2032 0.18796) (xy -0.19812 0.1778) (xy -0.17272 0.14224)
						(xy -0.1651 0.13462) (xy -0.1651 -0.7366) (xy -0.16256 -0.76835) (xy -0.1524 -0.8001) (xy -0.13716 -0.82804)
						(xy -0.11684 -0.85344) (xy -0.09144 -0.87376) (xy -0.0635 -0.889) (xy -0.03175 -0.89916) (xy 0 -0.9017)
						(xy 0.03175 -0.89916) (xy 0.0635 -0.889) (xy 0.09144 -0.87376) (xy 0.11684 -0.85344) (xy 0.13716 -0.82804)
						(xy 0.1524 -0.8001) (xy 0.16256 -0.76835) (xy 0.1651 -0.7366) (xy 0.1651 0.13462) (xy 0.17272 0.14224)
						(xy 0.19812 0.1778) (xy 0.2032 0.18796) (xy 0.20701 0.19685) (xy 0.21209 0.20701) (xy 0.2159 0.21717)
						(xy 0.21844 0.22733) (xy 0.22225 0.23876) (xy 0.22352 0.24892) (xy 0.22606 0.25908) (xy 0.22733 0.27051)
						(xy 0.22733 0.28067) (xy 0.2286 0.2921) (xy 0.22733 0.30353) (xy 0.22733 0.31369) (xy 0.22606 0.32512)
						(xy 0.22352 0.33528) (xy 0.22225 0.34544) (xy 0.21844 0.35687) (xy 0.2159 0.36703) (xy 0.21209 0.37719)
						(xy 0.20701 0.38735) (xy 0.2032 0.39624) (xy 0.19812 0.4064) (xy 0.17272 0.44196) (xy 0.1651 0.44958)
						(xy 0.1651 0.7366) (xy 0.16256 0.76835) (xy 0.1524 0.8001) (xy 0.13716 0.82804) (xy 0.11684 0.85344)
						(xy 0.09144 0.87376) (xy 0.0635 0.889) (xy 0.03175 0.89916)
					)
					(width 0)
					(fill yes)
				)
			)
		)
		(pad "59" smd custom
			(at -14.249908 4.106672 180)
			(size 0.1143 0.1143)
			(layers "F.Cu" "F.Mask" "F.Paste")
			(net "GND")
			(options
				(clearance outline)
				(anchor circle)
			)
			(primitives
				(gr_poly
					(pts
						(xy 0 0.9017) (xy -0.03175 0.89916) (xy -0.0635 0.889) (xy -0.09144 0.87376) (xy -0.11684 0.85344)
						(xy -0.13716 0.82804) (xy -0.1524 0.8001) (xy -0.16256 0.76835) (xy -0.1651 0.7366) (xy -0.1651 0.11938)
						(xy -0.17272 0.11176) (xy -0.19812 0.0762) (xy -0.2032 0.06604) (xy -0.20701 0.05715) (xy -0.21209 0.04699)
						(xy -0.2159 0.03683) (xy -0.21844 0.02667) (xy -0.22225 0.01524) (xy -0.22352 0.00508) (xy -0.22606 -0.00508)
						(xy -0.22733 -0.01651) (xy -0.22733 -0.02667) (xy -0.2286 -0.0381) (xy -0.22733 -0.04953) (xy -0.22733 -0.05969)
						(xy -0.22606 -0.07112) (xy -0.22352 -0.08128) (xy -0.22225 -0.09144) (xy -0.21844 -0.10287) (xy -0.2159 -0.11303)
						(xy -0.21209 -0.12319) (xy -0.20701 -0.13335) (xy -0.2032 -0.14224) (xy -0.19812 -0.1524) (xy -0.17272 -0.18796)
						(xy -0.1651 -0.19558) (xy -0.1651 -0.7366) (xy -0.16256 -0.76835) (xy -0.1524 -0.8001) (xy -0.13716 -0.82804)
						(xy -0.11684 -0.85344) (xy -0.09144 -0.87376) (xy -0.0635 -0.889) (xy -0.03175 -0.89916) (xy 0 -0.9017)
						(xy 0.03175 -0.89916) (xy 0.0635 -0.889) (xy 0.09144 -0.87376) (xy 0.11684 -0.85344) (xy 0.13716 -0.82804)
						(xy 0.1524 -0.8001) (xy 0.16256 -0.76835) (xy 0.1651 -0.7366) (xy 0.1651 -0.19685) (xy 0.17272 -0.18923)
						(xy 0.17907 -0.18034) (xy 0.18669 -0.17145) (xy 0.19177 -0.16256) (xy 0.19812 -0.15367) (xy 0.20828 -0.13335)
						(xy 0.21971 -0.10287) (xy 0.22225 -0.09271) (xy 0.22479 -0.08128) (xy 0.22606 -0.07112) (xy 0.2286 -0.05969)
						(xy 0.2286 -0.01651) (xy 0.22606 -0.00508) (xy 0.22479 0.00508) (xy 0.22225 0.01651) (xy 0.21971 0.02667)
						(xy 0.20828 0.05715) (xy 0.19812 0.07747) (xy 0.19177 0.08636) (xy 0.18669 0.09525) (xy 0.17907 0.10414)
						(xy 0.17272 0.11303) (xy 0.1651 0.12065) (xy 0.1651 0.7366) (xy 0.16256 0.76835) (xy 0.1524 0.8001)
						(xy 0.13716 0.82804) (xy 0.11684 0.85344) (xy 0.09144 0.87376) (xy 0.0635 0.889) (xy 0.03175 0.89916)
					)
					(width 0)
					(fill yes)
				)
			)
		)
		(pad "60" smd custom
			(at -13.949934 -4.106672 180)
			(size 0.1143 0.1143)
			(layers "F.Cu" "F.Mask" "F.Paste")
			(net "M_A_DQS_DN3")
			(options
				(clearance outline)
				(anchor circle)
			)
			(primitives
				(gr_poly
					(pts
						(xy 0 0.9017) (xy -0.03175 0.89916) (xy -0.0635 0.889) (xy -0.09144 0.87376) (xy -0.11684 0.85344)
						(xy -0.13716 0.82804) (xy -0.1524 0.8001) (xy -0.16256 0.76835) (xy -0.1651 0.7366) (xy -0.1651 0.19685)
						(xy -0.17272 0.18923) (xy -0.17907 0.18034) (xy -0.18669 0.17145) (xy -0.19177 0.16256) (xy -0.19812 0.15367)
						(xy -0.20828 0.13335) (xy -0.21971 0.10287) (xy -0.22225 0.09271) (xy -0.22479 0.08128) (xy -0.22606 0.07112)
						(xy -0.2286 0.05969) (xy -0.2286 0.01651) (xy -0.22606 0.00508) (xy -0.22479 -0.00508) (xy -0.22225 -0.01651)
						(xy -0.21971 -0.02667) (xy -0.20828 -0.05715) (xy -0.19812 -0.07747) (xy -0.19177 -0.08636) (xy -0.18669 -0.09525)
						(xy -0.17907 -0.10414) (xy -0.17272 -0.11303) (xy -0.1651 -0.12065) (xy -0.1651 -0.7366) (xy -0.16256 -0.76835)
						(xy -0.1524 -0.8001) (xy -0.13716 -0.82804) (xy -0.11684 -0.85344) (xy -0.09144 -0.87376) (xy -0.0635 -0.889)
						(xy -0.03175 -0.89916) (xy 0 -0.9017) (xy 0.03175 -0.89916) (xy 0.0635 -0.889) (xy 0.09144 -0.87376)
						(xy 0.11684 -0.85344) (xy 0.13716 -0.82804) (xy 0.1524 -0.8001) (xy 0.16256 -0.76835) (xy 0.1651 -0.7366)
						(xy 0.1651 -0.11938) (xy 0.17272 -0.11176) (xy 0.19812 -0.0762) (xy 0.2032 -0.06604) (xy 0.20701 -0.05715)
						(xy 0.21209 -0.04699) (xy 0.2159 -0.03683) (xy 0.21844 -0.02667) (xy 0.22225 -0.01524) (xy 0.22352 -0.00508)
						(xy 0.22606 0.00508) (xy 0.22733 0.01651) (xy 0.22733 0.02667) (xy 0.2286 0.0381) (xy 0.22733 0.04953)
						(xy 0.22733 0.05969) (xy 0.22606 0.07112) (xy 0.22352 0.08128) (xy 0.22225 0.09144) (xy 0.21844 0.10287)
						(xy 0.2159 0.11303) (xy 0.21209 0.12319) (xy 0.20701 0.13335) (xy 0.2032 0.14224) (xy 0.19812 0.1524)
						(xy 0.17272 0.18796) (xy 0.1651 0.19558) (xy 0.1651 0.7366) (xy 0.16256 0.76835) (xy 0.1524 0.8001)
						(xy 0.13716 0.82804) (xy 0.11684 0.85344) (xy 0.09144 0.87376) (xy 0.0635 0.889) (xy 0.03175 0.89916)
					)
					(width 0)
					(fill yes)
				)
			)
		)
		(pad "61" smd custom
			(at -13.64996 4.106672 180)
			(size 0.1143 0.1143)
			(layers "F.Cu" "F.Mask" "F.Paste")
			(net "GND")
			(options
				(clearance outline)
				(anchor circle)
			)
			(primitives
				(gr_poly
					(pts
						(xy 0 0.9017) (xy -0.03175 0.89916) (xy -0.0635 0.889) (xy -0.09144 0.87376) (xy -0.11684 0.85344)
						(xy -0.13716 0.82804) (xy -0.1524 0.8001) (xy -0.16256 0.76835) (xy -0.1651 0.7366) (xy -0.1651 -0.13462)
						(xy -0.17272 -0.14224) (xy -0.19812 -0.1778) (xy -0.2032 -0.18796) (xy -0.20701 -0.19685) (xy -0.21209 -0.20701)
						(xy -0.2159 -0.21717) (xy -0.21844 -0.22733) (xy -0.22225 -0.23876) (xy -0.22352 -0.24892) (xy -0.22606 -0.25908)
						(xy -0.22733 -0.27051) (xy -0.22733 -0.28067) (xy -0.2286 -0.2921) (xy -0.22733 -0.30353) (xy -0.22733 -0.31369)
						(xy -0.22606 -0.32512) (xy -0.22352 -0.33528) (xy -0.22225 -0.34544) (xy -0.21844 -0.35687) (xy -0.2159 -0.36703)
						(xy -0.21209 -0.37719) (xy -0.20701 -0.38735) (xy -0.2032 -0.39624) (xy -0.19812 -0.4064) (xy -0.17272 -0.44196)
						(xy -0.1651 -0.44958) (xy -0.1651 -0.7366) (xy -0.16256 -0.76835) (xy -0.1524 -0.8001) (xy -0.13716 -0.82804)
						(xy -0.11684 -0.85344) (xy -0.09144 -0.87376) (xy -0.0635 -0.889) (xy -0.03175 -0.89916) (xy 0 -0.9017)
						(xy 0.03175 -0.89916) (xy 0.0635 -0.889) (xy 0.09144 -0.87376) (xy 0.11684 -0.85344) (xy 0.13716 -0.82804)
						(xy 0.1524 -0.8001) (xy 0.16256 -0.76835) (xy 0.1651 -0.7366) (xy 0.1651 -0.44958) (xy 0.17272 -0.44196)
						(xy 0.19812 -0.4064) (xy 0.2032 -0.39624) (xy 0.20701 -0.38735) (xy 0.21209 -0.37719) (xy 0.2159 -0.36703)
						(xy 0.21844 -0.35687) (xy 0.22225 -0.34544) (xy 0.22352 -0.33528) (xy 0.22606 -0.32512) (xy 0.22733 -0.31369)
						(xy 0.22733 -0.30353) (xy 0.2286 -0.2921) (xy 0.22733 -0.28067) (xy 0.22733 -0.27051) (xy 0.22606 -0.25908)
						(xy 0.22352 -0.24892) (xy 0.22225 -0.23876) (xy 0.21844 -0.22733) (xy 0.2159 -0.21717) (xy 0.21209 -0.20701)
						(xy 0.20701 -0.19685) (xy 0.2032 -0.18796) (xy 0.19812 -0.1778) (xy 0.17272 -0.14224) (xy 0.1651 -0.13462)
						(xy 0.1651 0.7366) (xy 0.16256 0.76835) (xy 0.1524 0.8001) (xy 0.13716 0.82804) (xy 0.11684 0.85344)
						(xy 0.09144 0.87376) (xy 0.0635 0.889) (xy 0.03175 0.89916)
					)
					(width 0)
					(fill yes)
				)
			)
		)
		(pad "62" smd custom
			(at -13.349986 -4.106672 180)
			(size 0.1143 0.1143)
			(layers "F.Cu" "F.Mask" "F.Paste")
			(net "M_A_DQS_DP3")
			(options
				(clearance outline)
				(anchor circle)
			)
			(primitives
				(gr_poly
					(pts
						(xy 0 0.9017) (xy -0.03175 0.89916) (xy -0.0635 0.889) (xy -0.09144 0.87376) (xy -0.11684 0.85344)
						(xy -0.13716 0.82804) (xy -0.1524 0.8001) (xy -0.16256 0.76835) (xy -0.1651 0.7366) (xy -0.1651 0.44958)
						(xy -0.17272 0.44196) (xy -0.19812 0.4064) (xy -0.2032 0.39624) (xy -0.20701 0.38735) (xy -0.21209 0.37719)
						(xy -0.2159 0.36703) (xy -0.21844 0.35687) (xy -0.22225 0.34544) (xy -0.22352 0.33528) (xy -0.22606 0.32512)
						(xy -0.22733 0.31369) (xy -0.22733 0.30353) (xy -0.2286 0.2921) (xy -0.22733 0.28067) (xy -0.22733 0.27051)
						(xy -0.22606 0.25908) (xy -0.22352 0.24892) (xy -0.22225 0.23876) (xy -0.21844 0.22733) (xy -0.2159 0.21717)
						(xy -0.21209 0.20701) (xy -0.20701 0.19685) (xy -0.2032 0.18796) (xy -0.19812 0.1778) (xy -0.17272 0.14224)
						(xy -0.1651 0.13462) (xy -0.1651 -0.7366) (xy -0.16256 -0.76835) (xy -0.1524 -0.8001) (xy -0.13716 -0.82804)
						(xy -0.11684 -0.85344) (xy -0.09144 -0.87376) (xy -0.0635 -0.889) (xy -0.03175 -0.89916) (xy 0 -0.9017)
						(xy 0.03175 -0.89916) (xy 0.0635 -0.889) (xy 0.09144 -0.87376) (xy 0.11684 -0.85344) (xy 0.13716 -0.82804)
						(xy 0.1524 -0.8001) (xy 0.16256 -0.76835) (xy 0.1651 -0.7366) (xy 0.1651 0.13462) (xy 0.17272 0.14224)
						(xy 0.19812 0.1778) (xy 0.2032 0.18796) (xy 0.20701 0.19685) (xy 0.21209 0.20701) (xy 0.2159 0.21717)
						(xy 0.21844 0.22733) (xy 0.22225 0.23876) (xy 0.22352 0.24892) (xy 0.22606 0.25908) (xy 0.22733 0.27051)
						(xy 0.22733 0.28067) (xy 0.2286 0.2921) (xy 0.22733 0.30353) (xy 0.22733 0.31369) (xy 0.22606 0.32512)
						(xy 0.22352 0.33528) (xy 0.22225 0.34544) (xy 0.21844 0.35687) (xy 0.2159 0.36703) (xy 0.21209 0.37719)
						(xy 0.20701 0.38735) (xy 0.2032 0.39624) (xy 0.19812 0.4064) (xy 0.17272 0.44196) (xy 0.1651 0.44958)
						(xy 0.1651 0.7366) (xy 0.16256 0.76835) (xy 0.1524 0.8001) (xy 0.13716 0.82804) (xy 0.11684 0.85344)
						(xy 0.09144 0.87376) (xy 0.0635 0.889) (xy 0.03175 0.89916)
					)
					(width 0)
					(fill yes)
				)
			)
		)
	)
)
